;LEADER: 12 
;HEADER: 
;CODE  : ASCII 
;FILE  : 9324_DA0F0TMBIJ0_F0T_Motherboard_J_v01_20230324_0910-bd-18-15.drl for backdrilling ... from layer BOTTOM to layer GND6
;DESIGN: 9324_DA0F0TMBIJ0_F0T_Motherboard_J_v01_20230324_0910.brd
;MUST-NOT-CUT-LAYER = IN5,  MAX_DRILL_DEPTH = 20.25 MILS,  MFG_STUB_LENGTH = 0.00 MILS
;   BackdrillSize 1. = 15.700000 Tolerance = +0.000000/-0.000000 NON_PLATED MILS Quantity = 136
;   BackdrillSize 2. = 17.700000 Tolerance = +0.000000/-0.000000 NON_PLATED MILS Quantity = 8
;   BackdrillSize 3. = 21.870000 Tolerance = +0.000000/-0.000000 NON_PLATED MILS Quantity = 128
%
G90
X0369229Y0870606
X0367378Y0873810
X0363678Y0867401
X0359978Y0873810
X0356278Y0867401
X0352578Y0873810
X0371078Y0867401
X0365529Y0870606
X0361829Y0870606
X0358129Y0870606
X0354429Y0870606
X0350729Y0870606
X0384029Y0870606
X0382178Y0873810
X0376629Y0870606
X0374778Y0873810
X0406229Y0870606
X0404378Y0873810
X0398829Y0870606
X0396978Y0873810
X0393278Y0867401
X0389578Y0873810
X0385878Y0867401
X0380329Y0870606
X0378478Y0867401
X0372929Y0870606
X0408078Y0867401
X0402529Y0870606
X0400678Y0867401
X0395129Y0870606
X0391429Y0870606
X0387729Y0870606
X0507978Y0873810
X0506129Y0870606
X0500578Y0873810
X0498729Y0870606
X0493178Y0873810
X0491329Y0870606
X0485778Y0873810
X0483929Y0870606
X0478378Y0873810
X0530178Y0873810
X0528329Y0870606
X0522778Y0873810
X0520929Y0870606
X0515378Y0873810
X0513529Y0870606
X0476529Y0870606
X0509829Y0870606
X0504278Y0867401
X0502429Y0870606
X0496878Y0867401
X0495029Y0870606
X0489478Y0867401
X0487629Y0870606
X0482078Y0867401
X0480229Y0870606
X0532029Y0870606
X0526479Y0867401
X0524629Y0870606
X0519078Y0867401
X0517229Y0870606
X0511678Y0867401
X0474678Y0867401
X1349351Y0174098
X1355762Y0166698
X1349351Y0170398
X1342937Y0177799
X1349351Y0177798
X1352557Y0168548
X1352557Y0172248
X1346137Y0175949
X1360171Y0870606
X1358320Y0873810
X1352771Y0870606
X1350920Y0873810
X1345371Y0870606
X1343520Y0873810
X1339820Y0867401
X1336120Y0873810
X1332420Y0867401
X1369420Y0867401
X1365720Y0873810
X1328720Y0873810
X1362020Y0867401
X1356471Y0870606
X1354620Y0867401
X1349071Y0870606
X1347220Y0867401
X1341671Y0870606
X1337971Y0870606
X1334271Y0870606
X1330571Y0870606
X1371271Y0870606
X1367571Y0870606
X1363871Y0870606
X1326871Y0870606
X1469320Y0873810
X1467471Y0870606
X1461920Y0873810
X1460071Y0870606
X1454520Y0873810
X1452671Y0870606
X1471171Y0870606
X1465620Y0867401
X1463771Y0870606
X1458220Y0867401
X1456371Y0870606
X1450820Y0867401
X1382371Y0870606
X1380520Y0873810
X1374971Y0870606
X1373120Y0873810
X1384220Y0867401
X1378671Y0870606
X1376820Y0867401
X1484120Y0873810
X1482271Y0870606
X1476720Y0873810
X1474871Y0870606
X1506321Y0873810
X1504471Y0870606
X1498920Y0873810
X1497071Y0870606
X1491520Y0873810
X1489671Y0870606
X1485971Y0870606
X1480420Y0867401
X1478571Y0870606
X1473020Y0867401
X1508171Y0870606
X1502621Y0867401
X1500771Y0870606
X1495220Y0867401
X1493371Y0870606
X1487820Y0867401
M00
X0716698Y0177087
X0716698Y0173687
X0716698Y0189087
X0716698Y0200587
X0716698Y0212421
X0716698Y0185687
X0716698Y0197187
X0716698Y0209021
M00
X0230906Y1724763
X0246654Y1724763
X0262402Y1724763
X0230906Y1720039
X0246654Y1720039
X0262402Y1720039
X0238780Y1728700
X0254528Y1728700
X0270276Y1728700
X0238780Y1723976
X0254528Y1723976
X0270276Y1723976
X0352953Y1728700
X0337205Y1728700
X0321457Y1728700
X0305709Y1728700
X0352953Y1723976
X0345079Y1724763
X0337205Y1723976
X0329331Y1724763
X0321457Y1723976
X0313583Y1724763
X0305709Y1723976
X0297835Y1724763
X0345079Y1720039
X0329331Y1720039
X0313583Y1720039
X0297835Y1720039
X0278150Y1724763
X0278150Y1720039
X0286024Y1728700
X0286024Y1723976
X0550197Y1714527
X0534449Y1714527
X0518701Y1714527
X0502953Y1714527
X0550197Y1709803
X0542323Y1710590
X0534449Y1709803
X0526575Y1710590
X0518701Y1709803
X0510827Y1710590
X0502953Y1709803
X0495079Y1710590
X0542323Y1705866
X0526575Y1705866
X0510827Y1705866
X0495079Y1705866
X0569882Y1714527
X0569882Y1709803
X0562008Y1710590
X0562008Y1705866
X0617126Y1714527
X0601378Y1714527
X0585630Y1714527
X0617126Y1709803
X0609252Y1710590
X0601378Y1709803
X0593504Y1710590
X0585630Y1709803
X0577756Y1710590
X0609252Y1705866
X0593504Y1705866
X0577756Y1705866
X1262402Y1728700
X1246654Y1728700
X1270276Y1724763
X1262402Y1723976
X1254528Y1724763
X1246654Y1723976
X1238780Y1724763
X1270276Y1720039
X1254528Y1720039
X1238780Y1720039
X1360827Y1728700
X1345079Y1728700
X1329331Y1728700
X1313583Y1728700
X1360827Y1723976
X1352953Y1724763
X1345079Y1723976
X1337205Y1724763
X1329331Y1723976
X1321457Y1724763
X1313583Y1723976
X1305709Y1724763
X1352953Y1720039
X1337205Y1720039
X1321457Y1720039
X1305709Y1720039
X1293898Y1728700
X1278150Y1728700
X1293898Y1723976
X1286024Y1724763
X1278150Y1723976
X1286024Y1720039
X1558071Y1714527
X1542323Y1714527
X1526575Y1714527
X1510827Y1714527
X1558071Y1709803
X1550197Y1710590
X1542323Y1709803
X1534449Y1710590
X1526575Y1709803
X1518701Y1710590
X1510827Y1709803
X1502953Y1710590
X1550197Y1705866
X1534449Y1705866
X1518701Y1705866
X1502953Y1705866
X1569882Y1710590
X1569882Y1705866
X1625000Y1714527
X1609252Y1714527
X1593504Y1714527
X1577756Y1714527
X1625000Y1709803
X1617126Y1710590
X1609252Y1709803
X1601378Y1710590
X1593504Y1709803
X1585630Y1710590
X1577756Y1709803
X1617126Y1705866
X1601378Y1705866
X1585630Y1705866
M30
